# T6G (Grand Teton) — schematic parts with pin connectivity, parts 6831–6982 of 8303; source: Cadence DE-HDL packaged netlist (pstxprt.dat, pstxnet.dat, pstchip.dat)

R3472  Q_RES  0 5% EMPTY  pkg 0402LF  page 126 : 1 = GND ; 2 = GPU_WP_HW_CTRL_ISO_N
R3473  Q_RES  100K 1% EMPTY  pkg 0402LF  page 126 : 1 = GPU_PRSNT_N ; 2 = GND
R3474  Q_RES  4.7K 5% CHIP  pkg 0402LF  page 126 : 1 = P3V3_AUX ; 2 = GPU_PRSNT
R3475  Q_RES  100K 1% CHIP  pkg 0402LF  page 126 : 1 = P3V3_AUX ; 2 = GPU_PRSNT_N_ISO
R3476  Q_RES  33.2 1% CHIP  pkg 0402LF  page 81 : 1 = GPU_FPGA_THERM_OVERT_ISO_R_N ; 2 = GPU_FPGA_THERM_OVERT_ISO_N
R3477  Q_RES  33.2 1% CHIP  pkg 0402LF  page 81 : 1 = GPU_NVS_PWR_BRAKE_N ; 2 = GPU_NVS_PWR_BRAKE_R_N
R3478  Q_RES  33.2 1% CHIP  pkg 0402LF  page 81 : 1 = GPU_FPGA_EROT_RST_N ; 2 = GPU_FPGA_EROT_RST_R_N
R3479  Q_RES  33.2 1% CHIP  pkg 0402LF  page 81 : 1 = GPU_BASE_STBY_EN_R ; 2 = GPU_BASE_STBY_EN
R3480  Q_RES  33.2 1% CHIP  pkg 0402LF  page 81 : 1 = GPU_BASE_HMC_READY_ISO_R ; 2 = GPU_BASE_HMC_READY_ISO
R3481  Q_RES  33.2 1% CHIP  pkg 0402LF  page 81 : 1 = GPU_HMC_PRSNT_ISO_R_N ; 2 = GPU_HMC_PRSNT_ISO_N
R3482  Q_RES  33.2 1% CHIP  pkg 0402LF  page 81 : 1 = GPU_FPGA_BOOT_EN_R ; 2 = GPU_FPGA_BOOT_EN
R3483  Q_RES  33.2 1% CHIP  pkg 0402LF  page 81 : 1 = GPU_FPGA_EROT_RECOV_N ; 2 = GPU_FPGA_EROT_RECOV_R_N
R3484  Q_RES  33.2 1% CHIP  pkg 0402LF  page 81 : 1 = GPU_FPGA_OVERT_ISO_R_N ; 2 = GPU_FPGA_OVERT_ISO_N
R3485  Q_RES  33.2 1% CHIP  pkg 0402LF  page 81 : 1 = GPU_WP_HW_CTRL_R_N ; 2 = GPU_WP_HW_CTRL_N
R3486  Q_RES  33.2 1% CHIP  pkg 0402LF  page 81 : 1 = GPU_PRSNT_N_ISO_R ; 2 = GPU_PRSNT_N_ISO
R3487  Q_RES  10K 1% CHIP  pkg 0402LF  page 126 : 1 = P3V3_AUX ; 2 = GPU_PRSNT_N
R3488  Q_RES  1K 1% CHIP  pkg 0402LF  page 129 : 1 = P3V3_AUX ; 2 = GPU_FPGA_EROT_RST_N
R3489  Q_RES  100K 1% EMPTY  pkg 0402LF  page 129 : 1 = GPU_FPGA_EROT_RST_N ; 2 = GND
R3490  Q_RES  1K 1% CHIP  pkg 0402LF  page 129 : 1 = P3V3_AUX ; 2 = GPU_FPGA_EROT_RECOV_N
R3491  Q_RES  100K 1% EMPTY  pkg 0402LF  page 129 : 1 = GPU_FPGA_EROT_RECOV_N ; 2 = GND
R3492  Q_RES  54.9K 1% CHIP  pkg 0402LF  page 129 : 1 = P3V3_AUX ; 2 = GPU_FPGA_EROT_RST_BUF_R_N
R3493  Q_RES  100K 1% EMPTY  pkg 0402LF  page 129 : 1 = GPU_FPGA_EROT_RST_BUF_R_N ; 2 = GND
R3494  Q_RES  54.9K 1% CHIP  pkg 0402LF  page 129 : 1 = P3V3_AUX ; 2 = GPU_FPGA_EROT_RECOV_BUF_R_N
R3495  Q_RES  100K 1% EMPTY  pkg 0402LF  page 129 : 1 = GPU_FPGA_EROT_RECOV_BUF_R_N ; 2 = GND
R3496  Q_RES  33.2 1% CHIP  pkg 0402LF  page 129 : 1 = GPU_FPGA_EROT_RST_BUF_R_N ; 2 = GPU_FPGA_EROT_RST_BUF_N
R3497  Q_RES  33.2 1% CHIP  pkg 0402LF  page 129 : 1 = GPU_FPGA_EROT_RECOV_BUF_R_N ; 2 = GPU_FPGA_EROT_RECOV_BUF_N
R3498  Q_RES  54.9K 1% CHIP  pkg 0402LF  page 126 : 1 = P3V3_AUX ; 2 = GPU_FPGA_THERM_OVERT_N
R3499  Q_RES  0 5% CHIP  pkg 0402LF  page 245 : 1 = GPU_BASE_ID1 ; 2 = GPU_BASE_ID1_R
R3500  Q_RES  4.7K 5% CHIP  pkg 0402LF  page 247 : 1 = P3V3_OCP_SFF ; 2 = SMB_OCP_SFF_3V3AUX_BUF_SCL
R3501  Q_RES  4.7K 5% CHIP  pkg 0402LF  page 247 : 1 = P3V3_OCP_SFF ; 2 = SMB_OCP_SFF_3V3AUX_BUF_SDA
R3502  Q_RES  100K 1% EMPTY  pkg 0402LF  page 126 : 1 = GPU_FPGA_EROT_FATALERR_N ; 2 = GND
R3503  Q_RES  4.7K 5% CHIP  pkg 0402LF  page 126 : 1 = P3V3_AUX ; 2 = GPU_FPGA_EROT_FATALERR
R3504  Q_RES  100K 1% CHIP  pkg 0402LF  page 126 : 1 = P3V3_AUX ; 2 = GPU_FPGA_EROT_FATALERR_ISO_N
R3505  Q_RES  33.2 1% CHIP  pkg 0402LF  page 81 : 1 = GPU_FPGA_EROT_FATALERR_ISO_R_N ; 2 = GPU_FPGA_EROT_FATALERR_ISO_N
R3506  Q_RES  4.7K 5% EMPTY  pkg 0402LF  page 130 : 1 = P3V3_AUX ; 2 = GPU_FPGA_RST_R_N
R3507  Q_RES  10K 1% CHIP  pkg 0402LF  page 130 : 1 = GPU_FPGA_RST_R_N ; 2 = GND
R3508  Q_RES  54.9K 1% CHIP  pkg 0402LF  page 130 : 1 = FM_GPU_PWR_EN_R1 ; 2 = GND
R3509  Q_RES  10K 1% CHIP  pkg 0402LF  page 130 : 1 = GPU_FPGA_RST_R1_BUF_N ; 2 = GND
R3510  Q_RES  54.9K 1% CHIP  pkg 0402LF  page 127 : 1 = P3V3_AUX ; 2 = FM_SMB_1_ALERT_GPU_N
R3511  Q_RES  54.9K 1% CHIP  pkg 0402LF  page 127 : 1 = GPU_FPGA_READY ; 2 = GND
R3512  Q_RES  100K 1% EMPTY  pkg 0402LF  page 127 : 1 = P3V3_AUX ; 2 = FM_GPU_PWRGD
R3513  Q_RES  54.9K 1% CHIP  pkg 0402LF  page 127 : 1 = FM_GPU_PWRGD ; 2 = GND
R3514  Q_RES  54.9K 1% CHIP  pkg 0402LF  page 127 : 1 = P3V3_AUX ; 2 = FM_SMB_2_ALERT_GPU_N
R3515  Q_RES  49.9 1% CHIP  pkg 0402LF  page 128 : 1 = FM_SWB_PWR_EN_R1_BUF ; 2 = FM_SWB_PWR_EN_R_BUF
R3516  Q_RES  0 5% CHIP  pkg 0402LF  page 245 : 1 = GPU_BASE_ID0 ; 2 = GPU_BASE_ID0_R
R3517  Q_RES  0 5% CHIP  pkg 0402LF  page 245 : 1 = GPU_PEX_STRAP1 ; 2 = GPU_PEX_STRAP1_R
R3518  Q_RES  0 5% CHIP  pkg 0402LF  page 245 : 1 = GPU_PEX_STRAP0 ; 2 = GPU_PEX_STRAP0_R
R3519  Q_RES  4.7K 5% CHIP  pkg 0402LF  page 247 : 1 = P3V3_OCP_V3_2 ; 2 = SMB_OCP_V3_2_3V3AUX_BUF_SCL
R3520  Q_RES  4.7K 5% CHIP  pkg 0402LF  page 247 : 1 = P3V3_OCP_V3_2 ; 2 = SMB_OCP_V3_2_3V3AUX_BUF_SDA
R3521  Q_RES  54.9K 1% CHIP  pkg 0402LF  page 248 : 1 = P3V3_AUX ; 2 = SMB_2_BMC_GPU_BUF_R_SCL
R3522  Q_RES  54.9K 1% CHIP  pkg 0402LF  page 248 : 1 = P3V3_AUX ; 2 = SMB_2_BMC_GPU_BUF_R_SDA
R3523  Q_RES  54.9K 1% CHIP  pkg 0402LF  page 248 : 1 = P3V3_AUX ; 2 = SMB_1_BMC_GPU_BUF_R_SCL
R3524  Q_RES  54.9K 1% CHIP  pkg 0402LF  page 248 : 1 = P3V3_AUX ; 2 = SMB_1_BMC_GPU_BUF_R_SDA
R3525  Q_RES  54.9K 1% CHIP  pkg 0402LF  page 126 : 1 = P3V3_AUX ; 2 = GPU_FPGA_EROT_FATALERR_N
R3526  Q_RES  0 5% CHIP  pkg 0402LF  page 250 : 1 = SMB_PCIE0_3V3AUX_SCL_R5 ; 2 = SMB_SENSOR_E1S_3V3AUX_SCL
R3527  Q_RES  0 5% CHIP  pkg 0402LF  page 250 : 1 = SMB_PCIE0_3V3AUX_SDA_R5 ; 2 = SMB_SENSOR_E1S_3V3AUX_SDA
R3529  Q_RES  10K 1% CHIP  pkg 0402LF  page 148 : 1 = P3V3_AUX ; 2 = SMB_PCIE_E1S_ISO_EN_R
R3530  Q_RES  4.7K 5% CHIP  pkg 0402LF  page 148 : 1 = P3V3_E1S_0 ; 2 = SMB_E1S_3V3AUX_ISO_SCL_R
R3531  Q_RES  200K 1% EMPTY  pkg 0402LF  page 148 : 1 = SMB_PCIE_E1S_ISO_EN ; 2 = SMB_PCIE_E1S_ISO_EN_R
R3532  Q_RES  4.7K 5% CHIP  pkg 0402LF  page 148 : 1 = P3V3_E1S_0 ; 2 = SMB_E1S_3V3AUX_ISO_SDA_R
R3533  Q_RES  33.2 1% CHIP  pkg 0402LF  page 148 : 1 = SMB_E1S_3V3AUX_ISO_SCL_R ; 2 = SMB_E1S_3V3AUX_ISO_SCL
R3534  Q_RES  33.2 1% CHIP  pkg 0402LF  page 148 : 1 = SMB_E1S_3V3AUX_ISO_SDA_R ; 2 = SMB_E1S_3V3AUX_ISO_SDA
R3535  Q_RES  2.2K 5% CHIP  pkg 0402LF  page 250 : 1 = P3V3_AUX ; 2 = SMB_SENSOR_E1S_3V3AUX_SCL
R3536  Q_RES  2.2K 5% CHIP  pkg 0402LF  page 250 : 1 = P3V3_AUX ; 2 = SMB_SENSOR_E1S_3V3AUX_SDA
R3553  Q_RES  33.2 1% CHIP  pkg 0402LF  page 235 : 1 = SMB_LM75_3_3V3AUX_SCL ; 2 = SMB_LM75_3_3V3AUX_SCL_R1
R3554  Q_RES  33.2 1% CHIP  pkg 0402LF  page 235 : 1 = SMB_LM75_3_3V3AUX_SDA ; 2 = SMB_LM75_3_3V3AUX_SDA_R1
R3559  Q_RES  0 5% CHIP  pkg 0402LF  page 237 : 1 = OCP_V3_2_P3V3_ADC_ALERT_R ; 2 = OCP_V3_2_P3V3_P12V_ADC_R_ALERT
R3560  Q_RES  0 5% CHIP  pkg 0402LF  page 237 : 1 = M2_0_P3V3_ADC_ALERT_R ; 2 = M2_0_P3V3_ADC_ALERT
R3561  Q_RES  0 5% CHIP  pkg 0402LF  page 237 : 1 = P12V_SCM_ADC_ALERT_R ; 2 = P12V_SCM_ADC_ALERT
R3563  Q_RES  0 5% CHIP  pkg 0402LF  page 236 : 1 = OCP_SFF_P3V3_ADC_ALERT_R ; 2 = OCP_SFF_P3V3_P12V_ADC_R_ALERT
R3568  Q_RES  0 5% CHIP  pkg 0402LF  page 237 : 1 = SMB_INA230_3_3V3AUX_SCL_R ; 2 = SMB_INA230_3_3V3AUX_SCL_R1
R3569  Q_RES  0 5% CHIP  pkg 0402LF  page 237 : 1 = SMB_INA230_3_3V3AUX_SDA_R ; 2 = SMB_INA230_3_3V3AUX_SDA_R1
R3570  Q_RES  10 1% CHIP  pkg 0402LF  page 237 : 1 = P3V3_OCP_V3_2_R ; 2 = VSENSE_P12V_INA230_3_INP
R3571  Q_RES  10 1% CHIP  pkg 0402LF  page 237 : 1 = P3V3_OCP_V3_2 ; 2 = VSENSE_P12V_INA230_3_INN
R3572  Q_RES  0 5% CHIP  pkg 0402LF  page 237 : 1 = SMB_INA230_4_3V3AUX_SCL_R ; 2 = SMB_INA230_4_3V3AUX_SCL_R1
R3573  Q_RES  0 5% CHIP  pkg 0402LF  page 237 : 1 = SMB_INA230_4_3V3AUX_SDA_R ; 2 = SMB_INA230_4_3V3AUX_SDA_R1
R3574  Q_RES  10 1% CHIP  pkg 0402LF  page 237 : 1 = P3V3 ; 2 = VSENSE_P12V_INA230_4_INP
R3575  Q_RES  10 1% CHIP  pkg 0402LF  page 237 : 1 = P3V3_M2_0 ; 2 = VSENSE_P12V_INA230_4_INN
R3576  Q_RES  0 5% CHIP  pkg 0402LF  page 237 : 1 = SMB_INA230_5_3V3AUX_SCL_R ; 2 = SMB_INA230_5_3V3AUX_SCL_R1
R3577  Q_RES  0 5% CHIP  pkg 0402LF  page 237 : 1 = SMB_INA230_5_3V3AUX_SDA_R ; 2 = SMB_INA230_5_3V3AUX_SDA_R1
R3578  Q_RES  10 1% CHIP  pkg 0402LF  page 237 : 1 = P12V_SCM_R ; 2 = VSENSE_P12V_INA230_5_INP
R3579  Q_RES  10 1% CHIP  pkg 0402LF  page 237 : 1 = P12V_SCM ; 2 = VSENSE_P12V_INA230_5_INN
R3580  Q_RES  0 5% CHIP  pkg 0402LF  page 250 : 1 = SMB_INA230_3V3AUX_SCL_R ; 2 = SMB_INA230_3V3AUX_SCL
R3581  Q_RES  0 5% CHIP  pkg 0402LF  page 250 : 1 = SMB_INA230_3V3AUX_SDA_R ; 2 = SMB_INA230_3V3AUX_SDA
R3582  Q_RES  2.2K 5% CHIP  pkg 0402LF  page 250 : 1 = P3V3_AUX ; 2 = SMB_IOEXP_3V3AUX_SCL
R3583  Q_RES  2.2K 5% CHIP  pkg 0402LF  page 250 : 1 = P3V3_AUX ; 2 = SMB_IOEXP_3V3AUX_SDA
R3586  Q_RES  33.2 1% CHIP  pkg 0402LF  page 251 : 1 = SMB_INA230_3V3AUX_SCL ; 2 = SMB_INA230_1_3V3AUX_SCL_R
R3587  Q_RES  33.2 1% CHIP  pkg 0402LF  page 251 : 1 = SMB_INA230_3V3AUX_SDA ; 2 = SMB_INA230_1_3V3AUX_SDA_R
R3588  Q_RES  33.2 1% CHIP  pkg 0402LF  page 251 : 1 = SMB_INA230_3V3AUX_SCL ; 2 = SMB_INA230_2_3V3AUX_SCL_R
R3589  Q_RES  33.2 1% CHIP  pkg 0402LF  page 251 : 1 = SMB_INA230_3V3AUX_SDA ; 2 = SMB_INA230_2_3V3AUX_SDA_R
R3590  Q_RES  33.2 1% CHIP  pkg 0402LF  page 251 : 1 = SMB_INA230_3V3AUX_SCL ; 2 = SMB_INA230_3_3V3AUX_SCL_R
R3591  Q_RES  33.2 1% CHIP  pkg 0402LF  page 251 : 1 = SMB_INA230_3V3AUX_SDA ; 2 = SMB_INA230_3_3V3AUX_SDA_R
R3592  Q_RES  33.2 1% CHIP  pkg 0402LF  page 251 : 1 = SMB_INA230_3V3AUX_SCL ; 2 = SMB_INA230_5_3V3AUX_SCL_R
R3593  Q_RES  33.2 1% CHIP  pkg 0402LF  page 251 : 1 = SMB_INA230_3V3AUX_SDA ; 2 = SMB_INA230_5_3V3AUX_SDA_R
R3594  Q_RES  33.2 1% CHIP  pkg 0402LF  page 251 : 1 = SMB_INA230_3V3AUX_SCL ; 2 = SMB_INA230_4_3V3AUX_SCL_R
R3595  Q_RES  33.2 1% CHIP  pkg 0402LF  page 251 : 1 = SMB_INA230_3V3AUX_SDA ; 2 = SMB_INA230_4_3V3AUX_SDA_R
R3600  Q_RES  0 5% CHIP  pkg 0402LF  page 236 : 1 = SMB_INA230_1_3V3AUX_SCL_R ; 2 = SMB_INA230_1_3V3AUX_SCL_R1
R3601  Q_RES  0 5% CHIP  pkg 0402LF  page 236 : 1 = SMB_INA230_1_3V3AUX_SDA_R ; 2 = SMB_INA230_1_3V3AUX_SDA_R1
R3602  Q_RES  10 1% CHIP  pkg 0402LF  page 236 : 1 = P3V3_OCP_SFF_R ; 2 = VSENSE_P3V3_INA230_1_INP
R3603  Q_RES  10 1% CHIP  pkg 0402LF  page 236 : 1 = P3V3_OCP_SFF ; 2 = VSENSE_P3V3_INA230_1_INN
R3608  Q_RES  4.7K 1% CHIP  pkg 0402LF  page 237 : 1 = GND ; 2 = INA230_3_A1
R3609  Q_RES  4.7K 1% EMPTY  pkg 0402LF  page 237 : 1 = GND ; 2 = INA230_3_A0
R3610  Q_RES  4.7K 1% EMPTY  pkg 0402LF  page 237 : 1 = GND ; 2 = INA230_4_A1
R3611  Q_RES  4.7K 1% CHIP  pkg 0402LF  page 237 : 1 = GND ; 2 = INA230_4_A0
R3612  Q_RES  4.7K 1% EMPTY  pkg 0402LF  page 237 : 1 = GND ; 2 = INA230_5_A1
R3613  Q_RES  4.7K 1% EMPTY  pkg 0402LF  page 237 : 1 = GND ; 2 = INA230_5_A0
R3616  Q_RES  4.7K 1% CHIP  pkg 0402LF  page 236 : 1 = GND ; 2 = INA230_1_A1
R3617  Q_RES  4.7K 1% EMPTY  pkg 0402LF  page 236 : 1 = GND ; 2 = INA230_1_A0
R3620  Q_RES  0 5% CHIP  pkg 0402LF  page 237 : 1 = INA230_3_A0 ; 2 = SMB_INA230_3_3V3AUX_SCL_R1
R3621  Q_RES  4.7K 1% EMPTY  pkg 0402LF  page 237 : 1 = P3V3_AUX ; 2 = INA230_4_A0
R3622  Q_RES  4.7K 1% CHIP  pkg 0402LF  page 237 : 1 = P3V3_AUX ; 2 = INA230_5_A0
R3623  Q_RES  4.7K 1% CHIP  pkg 0402LF  page 237 : 1 = P3V3_AUX ; 2 = INA230_4_A1
R3624  Q_RES  4.7K 1% CHIP  pkg 0402LF  page 237 : 1 = P3V3_AUX ; 2 = INA230_5_A1
R3627  Q_RES  4.7K 1% CHIP  pkg 0402LF  page 236 : 1 = P3V3_AUX ; 2 = INA230_1_A0
R3628  Q_RES  4.7K 1% EMPTY  pkg 0402LF  page 236 : 1 = P3V3_AUX ; 2 = INA230_1_A1
R3630  Q_RES  0 5% EMPTY  pkg 0402LF  page 141 : 1 = P12V_OCP_V3_2_EN_R ; 2 = P12V_OCP_V3_2_EN_2_R3
R3631  Q_RES  0 5% EMPTY  pkg 0402LF  page 141 : 1 = P3V3_OCP_V3_2_EN_R ; 2 = P3V3_OCP_EN_2
R3633  Q_RES  0.002 1% CHIP  pkg 2512LF  page 237 : 1 = P3V3_OCP_V3_2 ; 2 = P3V3_OCP_V3_2_R
R3634  Q_RES  0.002 1% CHIP  pkg 2512LF  page 237 : 1 = P3V3_M2_0 ; 2 = P3V3
R3635  Q_RES  0.002 1% CHIP  pkg 2512LF  page 237 : 1 = P12V_SCM ; 2 = P12V_SCM_R
R3645  Q_RES  0.002 1% CHIP  pkg 2512LF  page 236 : 1 = P3V3_OCP_SFF ; 2 = P3V3_OCP_SFF_R
R3651  Q_RES  0 5% CHIP  pkg 0402LF  page 234 : 1 = USB2_P0_R_DP ; 2 = USB2_HOST_BMC_B_DP
R3652  Q_RES  0 5% CHIP  pkg 0402LF  page 234 : 1 = USB2_P0_R_DN ; 2 = USB2_HOST_BMC_B_DN
R3653  Q_RES  680 1% CHIP  pkg 0402LF  page 234 : 1 = USB_HUB_RREF ; 2 = GND
R3654  Q_RES  33.2 1% CHIP  pkg 0402LF  page 234 : 1 = RST_USB_HUB_N ; 2 = RST_USB_HUB_R_N
R3655  Q_RES  0 5% CHIP  pkg 0402LF  page 234 : 1 = P3V3_AUX ; 2 = P3V3_AUX_USB_HUB
R3656  Q_RES  10K 1% EMPTY  pkg 0402LF  page 234 : 1 = P3V3_AUX ; 2 = USB_HUB_OVCUR1
R3657  Q_RES  10K 1% EMPTY  pkg 0402LF  page 234 : 1 = P3V3_AUX ; 2 = USB_HUB_OVCUR2
R3658  Q_RES  10K 1% EMPTY  pkg 0402LF  page 234 : 1 = P3V3_AUX ; 2 = USB_HUB_OVCUR3
R3659  Q_RES  10K 1% EMPTY  pkg 0402LF  page 234 : 1 = P3V3_AUX ; 2 = USB_HUB_OVCUR4
R3660  Q_RES  10K 1% CHIP  pkg 0402LF  page 234 : 1 = P3V3_AUX ; 2 = RST_USB_HUB_R_N
R3661  Q_RES  47K 0.1% EMPTY  pkg 0402LF  page 234 : 1 = GND ; 2 = RST_USB_HUB_R_N
R3662  Q_RES  0 5% CHIP  pkg 0402LF  page 234 : 1 = P3V3_AUX_USB_HUB ; 2 = USB_HUB_DVDD
R3663  Q_RES  10K 1% CHIP  pkg 0402LF  page 234 : 1 = P3V3_AUX ; 2 = USB_HUB_PSELF
R3664  Q_RES  10K 1% EMPTY  pkg 0402LF  page 234 : 1 = USB_HUB_PSELF ; 2 = GND
R3665  Q_RES  100K 1% CHIP  pkg 0402LF  page 234 : 1 = USB_HUB_PGANG ; 2 = GND
R3666  Q_RES  0 5% CHIP  pkg 0402LF  page 234 : 1 = USB_HUB_TEST ; 2 = GND
R3667  Q_RES  1K 1% EMPTY  pkg 0402LF  page 257 : 1 = P3V3_AUX ; 2 = ADC128_A1
R3668  Q_RES  1K 1% CHIP  pkg 0402LF  page 257 : 1 = ADC128_A1 ; 2 = GND
R3669  Q_RES  1K 1% EMPTY  pkg 0402LF  page 257 : 1 = P3V3_AUX ; 2 = ADC128_A0
R3670  Q_RES  1K 1% CHIP  pkg 0402LF  page 257 : 1 = ADC128_A0 ; 2 = GND
R3671  Q_RES  0 5% CHIP  pkg 0402LF  page 257 : 1 = SMB_SCM_2_R4_SDA ; 2 = SMB_SEN_TIC_3V3AUX_SDA
R3672  Q_RES  0 5% CHIP  pkg 0402LF  page 257 : 1 = SMB_SCM_2_R4_SCL ; 2 = SMB_SEN_TIC_3V3AUX_SCL
R3679  Q_RES  0 5% EMPTY  pkg 0402LF  page 257 : 1 = P12V_AUX_ADC ; 2 = P12V_AUX_ADC_MAM
R3680  Q_RES  0 5% CHIP  pkg 0402LF  page 257 : 1 = P12V_AUX_ADC ; 2 = P12V_AUX_ADC_TIC
R3681  Q_RES  0 5% EMPTY  pkg 0402LF  page 257 : 1 = P3V3_AUX_ADC ; 2 = P3V3_AUX_ADC_MAM
R3682  Q_RES  0 5% CHIP  pkg 0402LF  page 257 : 1 = P3V3_AUX_ADC ; 2 = P3V3_AUX_ADC_TIC
R3683  Q_RES  0 5% EMPTY  pkg 0402LF  page 257 : 1 = P3V3_ADC ; 2 = P3V3_ADC_MAM
R3684  Q_RES  0 5% CHIP  pkg 0402LF  page 257 : 1 = P3V3_ADC ; 2 = P3V3_ADC_TIC
R3685  Q_RES  0 5% EMPTY  pkg 0402LF  page 257 : 1 = P5V_ADC ; 2 = P5V_ADC_MAM
R3686  Q_RES  0 5% CHIP  pkg 0402LF  page 257 : 1 = P5V_ADC ; 2 = P5V_ADC_TIC
R3687  Q_RES  0 5% EMPTY  pkg 0402LF  page 257 : 1 = P1V581_PDB_ADC ; 2 = P3V3_PDB_AUX_ADC_MAM
